# T6G (Grand Teton) — schematic netlist excerpt (pin names and nets, part order shuffled) for the footprints in the layout excerpt that follows; sources: Cadence DE-HDL packaged netlist, KiCad conversion of 04192023_DAF0TMB3IC0_F0TG_MB_C_brd_V02_OCP.brd

R3469  Q_RES  49.9 1% CHIP  pkg 0402LF  page 128 : A = RST_PERST_0_SWB_BUF_R_N ; B = RST_PERST_0_SWB_BUF_N
C31  Q_CAP  0.1UF 25V 10% X7R  pkg 0402  page 235 : A = P3V3_AUX ; B = GND
C6528  Q_CAP_DIFFBUS  DIFF BUS_0.22UF 6.3V 20% X6S  pkg C0201  page 275 : \1\ = P5E_CPU0_P0_TX_BUF_C_DN<13> ; \2\ = P5E_CPU0_P0_TX_BUF_DN<13>

(kicad_pcb
	(version 20260206)
	(generator "pcbnew")
	(generator_version "10.0")
	(general
		(thickness 1.6)
		(legacy_teardrops no)
	)
	(paper "A4")
	(title_block
		(title "04192023_DAF0TMB3IC0_F0TG_MB_C_brd_V02_OCP.brd")
		(comment 1 "Grand Teton / footprints 3241-3243 of 8354")
	)
	(layers
		(0 "F.Cu" signal "TOP")
		(4 "In1.Cu" signal "GND")
		(6 "In2.Cu" signal "IN1")
		(8 "In3.Cu" signal "GND1")
		(10 "In4.Cu" signal "IN2")
		(12 "In5.Cu" signal "GND2")
		(14 "In6.Cu" signal "IN3")
		(16 "In7.Cu" signal "GND3")
		(18 "In8.Cu" signal "VCC")
		(20 "In9.Cu" signal "VCC1")
		(22 "In10.Cu" signal "GND4")
		(24 "In11.Cu" signal "IN4")
		(26 "In12.Cu" signal "GND5")
		(28 "In13.Cu" signal "IN5")
		(30 "In14.Cu" signal "GND6")
		(32 "In15.Cu" signal "IN6")
		(34 "In16.Cu" signal "GND7")
		(2 "B.Cu" signal "BOTTOM")
		(9 "F.Adhes" user "F.Adhesive")
		(11 "B.Adhes" user "B.Adhesive")
		(13 "F.Paste" user "Package Geometry/Pastemask Top")
		(15 "B.Paste" user "Package Geometry/Pastemask Bottom")
		(5 "F.SilkS" user "Ref Des/Silkscreen Top")
		(7 "B.SilkS" user "Ref Des/Silkscreen Bottom")
		(1 "F.Mask" user "Board Geometry/Soldermask Top")
		(3 "B.Mask" user "Board Geometry/Soldermask Bottom")
		(17 "Dwgs.User" user "User.Drawings")
		(19 "Cmts.User" user "User.Comments")
		(21 "Eco1.User" user "User.Eco1")
		(23 "Eco2.User" user "User.Eco2")
		(25 "Edge.Cuts" user "Board Geometry/Outline")
		(27 "Margin" user)
		(31 "F.CrtYd" user "Package Geometry/Place Bound Top")
		(29 "B.CrtYd" user "Package Geometry/Place Bound Bottom")
		(35 "F.Fab" user "Ref Des/Assembly Top")
		(33 "B.Fab" user "Ref Des/Assembly Bottom")
	)
	(footprint ""
		(layer "F.Cu")
		(at 52.78501 -437.642)
		(property "Reference" "R3469"
			(at 0 0 0)
			(layer "F.SilkS")
			(hide yes)
			(effects
				(font
					(size 1.27 1.27)
				)
			)
		)
		(property "Value" ""
			(at 0 0 0)
			(layer "F.Fab")
			(effects
				(font
					(size 1.27 1.27)
				)
			)
		)
		(duplicate_pad_numbers_are_jumpers no)
		(fp_line
			(start -0.7874 -0.4064)
			(end 0.7874 -0.4064)
			(stroke
				(width 0.1524)
				(type default)
			)
			(layer "F.SilkS")
		)
		(fp_line
			(start -0.7874 0.4064)
			(end -0.7874 -0.4064)
			(stroke
				(width 0.1524)
				(type default)
			)
			(layer "F.SilkS")
		)
		(fp_line
			(start 0.7874 -0.4064)
			(end 0.7874 0.4064)
			(stroke
				(width 0.1524)
				(type default)
			)
			(layer "F.SilkS")
		)
		(fp_line
			(start 0.7874 0.4064)
			(end -0.7874 0.4064)
			(stroke
				(width 0.1524)
				(type default)
			)
			(layer "F.SilkS")
		)
		(fp_line
			(start -0.67945 -0.305054)
			(end -0.12065 -0.305054)
			(stroke
				(width 0.1)
				(type default)
			)
			(layer "F.Fab")
		)
		(fp_line
			(start -0.67945 0.3048)
			(end -0.67945 -0.305054)
			(stroke
				(width 0.1)
				(type default)
			)
			(layer "F.Fab")
		)
		(fp_line
			(start -0.12065 -0.305054)
			(end -0.12065 -0.2794)
			(stroke
				(width 0.1)
				(type default)
			)
			(layer "F.Fab")
		)
		(fp_line
			(start -0.12065 -0.2794)
			(end 0.12065 -0.2794)
			(stroke
				(width 0.1)
				(type default)
			)
			(layer "F.Fab")
		)
		(fp_line
			(start -0.12065 0.2794)
			(end -0.12065 0.3048)
			(stroke
				(width 0.1)
				(type default)
			)
			(layer "F.Fab")
		)
		(fp_line
			(start -0.12065 0.3048)
			(end -0.67945 0.3048)
			(stroke
				(width 0.1)
				(type default)
			)
			(layer "F.Fab")
		)
		(fp_line
			(start 0.120396 0.2794)
			(end -0.12065 0.2794)
			(stroke
				(width 0.1)
				(type default)
			)
			(layer "F.Fab")
		)
		(fp_line
			(start 0.120396 0.3048)
			(end 0.120396 0.2794)
			(stroke
				(width 0.1)
				(type default)
			)
			(layer "F.Fab")
		)
		(fp_line
			(start 0.12065 -0.3048)
			(end 0.67945 -0.3048)
			(stroke
				(width 0.1)
				(type default)
			)
			(layer "F.Fab")
		)
		(fp_line
			(start 0.12065 -0.2794)
			(end 0.12065 -0.3048)
			(stroke
				(width 0.1)
				(type default)
			)
			(layer "F.Fab")
		)
		(fp_line
			(start 0.67945 -0.3048)
			(end 0.67945 0.3048)
			(stroke
				(width 0.1)
				(type default)
			)
			(layer "F.Fab")
		)
		(fp_line
			(start 0.67945 0.3048)
			(end 0.120396 0.3048)
			(stroke
				(width 0.1)
				(type default)
			)
			(layer "F.Fab")
		)
		(pad "1" smd circle
			(at -0.40005 0)
			(size 0 0)
			(layers "F.Cu" "F.Mask" "F.Paste")
			(net "RST_PERST_0_SWB_BUF_R_N")
		)
		(pad "2" smd circle
			(at 0.40005 0)
			(size 0 0)
			(layers "F.Cu" "F.Mask" "F.Paste")
			(net "RST_PERST_0_SWB_BUF_N")
		)
	)
	(footprint ""
		(layer "F.Cu")
		(at 343.590626 -416.899344 -90)
		(property "Reference" "C6528"
			(at 0 0 270)
			(layer "F.SilkS")
			(hide yes)
			(effects
				(font
					(size 1.27 1.27)
				)
			)
		)
		(property "Value" ""
			(at 0 0 270)
			(layer "F.Fab")
			(effects
				(font
					(size 1.27 1.27)
				)
			)
		)
		(duplicate_pad_numbers_are_jumpers no)
		(fp_line
			(start -0.299974 0.150114)
			(end -0.299974 -0.150114)
			(stroke
				(width 0.1)
				(type default)
			)
			(layer "F.Fab")
		)
		(fp_line
			(start 0.299974 0.150114)
			(end -0.299974 0.150114)
			(stroke
				(width 0.1)
				(type default)
			)
			(layer "F.Fab")
		)
		(fp_line
			(start -0.299974 -0.150114)
			(end 0.299974 -0.150114)
			(stroke
				(width 0.1)
				(type default)
			)
			(layer "F.Fab")
		)
		(fp_line
			(start 0.299974 -0.150114)
			(end 0.299974 0.150114)
			(stroke
				(width 0.1)
				(type default)
			)
			(layer "F.Fab")
		)
		(pad "1" smd rect
			(at -0.2667 0 270)
			(size 0.3048 0.381)
			(layers "F.Cu" "F.Mask" "F.Paste")
			(net "P5E_CPU0_P0_TX_BUF_C_DN<13>")
		)
		(pad "2" smd rect
			(at 0.2667 0 270)
			(size 0.3048 0.381)
			(layers "F.Cu" "F.Mask" "F.Paste")
			(net "P5E_CPU0_P0_TX_BUF_DN<13>")
		)
	)
	(footprint ""
		(layer "F.Cu")
		(at 117.913912 -17.784064)
		(property "Reference" "C31"
			(at 0 0 0)
			(layer "F.SilkS")
			(hide yes)
			(effects
				(font
					(size 1.27 1.27)
				)
			)
		)
		(property "Value" ""
			(at 0 0 0)
			(layer "F.Fab")
			(effects
				(font
					(size 1.27 1.27)
				)
			)
		)
		(duplicate_pad_numbers_are_jumpers no)
		(fp_line
			(start -0.7874 -0.4064)
			(end 0.7874 -0.4064)
			(stroke
				(width 0.1524)
				(type default)
			)
			(layer "F.SilkS")
		)
		(fp_line
			(start -0.7874 0.4064)
			(end -0.7874 -0.4064)
			(stroke
				(width 0.1524)
				(type default)
			)
			(layer "F.SilkS")
		)
		(fp_line
			(start 0.7874 -0.4064)
			(end 0.7874 0.4064)
			(stroke
				(width 0.1524)
				(type default)
			)
			(layer "F.SilkS")
		)
		(fp_line
			(start 0.7874 0.4064)
			(end -0.7874 0.4064)
			(stroke
				(width 0.1524)
				(type default)
			)
			(layer "F.SilkS")
		)
		(fp_line
			(start -0.67945 -0.305054)
			(end -0.12065 -0.305054)
			(stroke
				(width 0.1)
				(type default)
			)
			(layer "F.Fab")
		)
		(fp_line
			(start -0.67945 0.3048)
			(end -0.67945 -0.305054)
			(stroke
				(width 0.1)
				(type default)
			)
			(layer "F.Fab")
		)
		(fp_line
			(start -0.12065 -0.305054)
			(end -0.12065 -0.2794)
			(stroke
				(width 0.1)
				(type default)
			)
			(layer "F.Fab")
		)
		(fp_line
			(start -0.12065 -0.2794)
			(end 0.12065 -0.2794)
			(stroke
				(width 0.1)
				(type default)
			)
			(layer "F.Fab")
		)
		(fp_line
			(start -0.12065 0.2794)
			(end -0.12065 0.3048)
			(stroke
				(width 0.1)
				(type default)
			)
			(layer "F.Fab")
		)
		(fp_line
			(start -0.12065 0.3048)
			(end -0.67945 0.3048)
			(stroke
				(width 0.1)
				(type default)
			)
			(layer "F.Fab")
		)
		(fp_line
			(start 0.120396 0.2794)
			(end -0.12065 0.2794)
			(stroke
				(width 0.1)
				(type default)
			)
			(layer "F.Fab")
		)
		(fp_line
			(start 0.120396 0.3048)
			(end 0.120396 0.2794)
			(stroke
				(width 0.1)
				(type default)
			)
			(layer "F.Fab")
		)
		(fp_line
			(start 0.12065 -0.3048)
			(end 0.67945 -0.3048)
			(stroke
				(width 0.1)
				(type default)
			)
			(layer "F.Fab")
		)
		(fp_line
			(start 0.12065 -0.2794)
			(end 0.12065 -0.3048)
			(stroke
				(width 0.1)
				(type default)
			)
			(layer "F.Fab")
		)
		(fp_line
			(start 0.67945 -0.3048)
			(end 0.67945 0.3048)
			(stroke
				(width 0.1)
				(type default)
			)
			(layer "F.Fab")
		)
		(fp_line
			(start 0.67945 0.3048)
			(end 0.120396 0.3048)
			(stroke
				(width 0.1)
				(type default)
			)
			(layer "F.Fab")
		)
		(pad "1" smd circle
			(at -0.40005 0)
			(size 0 0)
			(layers "F.Cu" "F.Mask" "F.Paste")
			(net "P3V3_AUX")
		)
		(pad "2" smd circle
			(at 0.40005 0)
			(size 0 0)
			(layers "F.Cu" "F.Mask" "F.Paste")
			(net "GND")
		)
	)
)
